FILE_TYPE = MULTI_PHYS_TABLE;

PART '74LVC1G32GW'

{========================================================================================}
:PACK_TYPE | VALUE         | MATERIAL | PART_NUMBER    = STANDARD         | LIFECYCLE        | PART_NUMBER   | JEDEC_TYPE | CLASS | DESCRIPTION                  | HEIGHT   | COMPONENT_TYPE | LEAD_LENGTH | DFM_EXCLUSION | DAY        ;
{========================================================================================}
 'SMLF'    | '74LVC1G32GW' | 'IC'     | 'ALVC1G32007'(!) = ''               | ''               | 'ALVC1G32007' |'SOT353_Q'| 'IC'  | 'IC(5P)74LVC1G32GW (SC70-5)' | '.044IN' | 'SMALLSMT'     | ''          | ''            | '20101005'
 'SMLF'    | '74LVC1G32GW' | 'EMPTY'  | 'ALVC1G32007'(!) = ''               | ''               | 'ALVC1G32007' |'SOT353_Q'| 'IO'  | 'IC(5P)74LVC1G32GW (SC70-5)' | '.044IN' | 'SMALLSMT'     | ''          | ''            | '20101005'

END_PART

END.

